(kicad_pcb
	(version 20260206)
	(generator "pcbnew")
	(generator_version "10.0")
	(general
		(thickness 1.6)
		(legacy_teardrops no)
	)
	(paper "A4")
	(title_block
		(title "Wiwynn_Tioga_Pass_MB.brd")
		(comment 1 "Tioga Pass / footprint 437 of 4770 (J1G3), pads 244-291 of 291")
	)
	(layers
		(0 "F.Cu" signal "TOP")
		(4 "In1.Cu" signal "L2GND")
		(6 "In2.Cu" signal "L3")
		(8 "In3.Cu" signal "L4GND")
		(10 "In4.Cu" signal "L5")
		(12 "In5.Cu" signal "L6GND")
		(14 "In6.Cu" signal "L7VCC")
		(16 "In7.Cu" signal "L8VCC")
		(18 "In8.Cu" signal "L9GND")
		(20 "In9.Cu" signal "L10")
		(22 "In10.Cu" signal "L11GND")
		(24 "In11.Cu" signal "L12")
		(26 "In12.Cu" signal "L13GND")
		(2 "B.Cu" signal "BOTTOM")
		(9 "F.Adhes" user "F.Adhesive")
		(11 "B.Adhes" user "B.Adhesive")
		(13 "F.Paste" user "Package Geometry/Pastemask Top")
		(15 "B.Paste" user "Package Geometry/Pastemask Bottom")
		(5 "F.SilkS" user "Ref Des/Silkscreen Top")
		(7 "B.SilkS" user "Ref Des/Silkscreen Bottom")
		(1 "F.Mask" user "Board Geometry/Soldermask Top")
		(3 "B.Mask" user "Board Geometry/Soldermask Bottom")
		(17 "Dwgs.User" user "User.Drawings")
		(19 "Cmts.User" user "User.Comments")
		(21 "Eco1.User" user "User.Eco1")
		(23 "Eco2.User" user "User.Eco2")
		(25 "Edge.Cuts" user "Board Geometry/Outline")
		(27 "Margin" user)
		(31 "F.CrtYd" user "Package Geometry/Place Bound Top")
		(29 "B.CrtYd" user "Package Geometry/Place Bound Bottom")
		(35 "F.Fab" user "Ref Des/Assembly Top")
		(33 "B.Fab" user "Ref Des/Assembly Bottom")
	)
	(footprint ""
		(layer "F.Cu")
		(at 29.699458 3.778758 90)
		(property "Reference" "J1G3"
			(at 7.054088 34.562542 0)
			(unlocked yes)
			(layer "F.SilkS")
			(effects
				(font
					(size 0.7874 0.5842)
					(thickness 0.1524)
				)
				(justify left)
			)
		)
		(property "Value" ""
			(at 0 0 90)
			(layer "F.Fab")
			(effects
				(font
					(size 1.27 1.27)
				)
			)
		)
		(duplicate_pad_numbers_are_jumpers no)
		(pad "241" smd rect
			(at 4.59994 86.700106 90)
			(size 1.8034 0.508)
			(layers "F.Cu" "F.Mask" "F.Paste")
			(net "GND")
		)
		(pad "242" smd rect
			(at 4.59994 87.54999 90)
			(size 1.8034 0.508)
			(layers "F.Cu" "F.Mask" "F.Paste")
			(net "M_J_DQ<32>")
		)
		(pad "243" smd rect
			(at 4.59994 88.399874 90)
			(size 1.8034 0.508)
			(layers "F.Cu" "F.Mask" "F.Paste")
			(net "GND")
		)
		(pad "244" smd rect
			(at 4.59994 89.250012 90)
			(size 1.8034 0.508)
			(layers "F.Cu" "F.Mask" "F.Paste")
			(net "M_J_DQS_DN<4>")
		)
		(pad "245" smd rect
			(at 4.59994 90.099896 90)
			(size 1.8034 0.508)
			(layers "F.Cu" "F.Mask" "F.Paste")
			(net "M_J_DQS_DP<4>")
		)
		(pad "246" smd rect
			(at 4.59994 90.950034 90)
			(size 1.8034 0.508)
			(layers "F.Cu" "F.Mask" "F.Paste")
			(net "GND")
		)
		(pad "247" smd rect
			(at 4.59994 91.799918 90)
			(size 1.8034 0.508)
			(layers "F.Cu" "F.Mask" "F.Paste")
			(net "M_J_DQ<38>")
		)
		(pad "248" smd rect
			(at 4.59994 92.650056 90)
			(size 1.8034 0.508)
			(layers "F.Cu" "F.Mask" "F.Paste")
			(net "GND")
		)
		(pad "249" smd rect
			(at 4.59994 93.49994 90)
			(size 1.8034 0.508)
			(layers "F.Cu" "F.Mask" "F.Paste")
			(net "M_J_DQ<34>")
		)
		(pad "250" smd rect
			(at 4.59994 94.350078 90)
			(size 1.8034 0.508)
			(layers "F.Cu" "F.Mask" "F.Paste")
			(net "GND")
		)
		(pad "251" smd rect
			(at 4.59994 95.199962 90)
			(size 1.8034 0.508)
			(layers "F.Cu" "F.Mask" "F.Paste")
			(net "M_J_DQ<44>")
		)
		(pad "252" smd rect
			(at 4.59994 96.0501 90)
			(size 1.8034 0.508)
			(layers "F.Cu" "F.Mask" "F.Paste")
			(net "GND")
		)
		(pad "253" smd rect
			(at 4.59994 96.899984 90)
			(size 1.8034 0.508)
			(layers "F.Cu" "F.Mask" "F.Paste")
			(net "M_J_DQ<40>")
		)
		(pad "254" smd rect
			(at 4.59994 97.750122 90)
			(size 1.8034 0.508)
			(layers "F.Cu" "F.Mask" "F.Paste")
			(net "GND")
		)
		(pad "255" smd rect
			(at 4.59994 98.600006 90)
			(size 1.8034 0.508)
			(layers "F.Cu" "F.Mask" "F.Paste")
			(net "M_J_DQS_DN<5>")
		)
		(pad "256" smd rect
			(at 4.59994 99.44989 90)
			(size 1.8034 0.508)
			(layers "F.Cu" "F.Mask" "F.Paste")
			(net "M_J_DQS_DP<5>")
		)
		(pad "257" smd rect
			(at 4.59994 100.300028 90)
			(size 1.8034 0.508)
			(layers "F.Cu" "F.Mask" "F.Paste")
			(net "GND")
		)
		(pad "258" smd rect
			(at 4.59994 101.149912 90)
			(size 1.8034 0.508)
			(layers "F.Cu" "F.Mask" "F.Paste")
			(net "M_J_DQ<46>")
		)
		(pad "259" smd rect
			(at 4.59994 102.00005 90)
			(size 1.8034 0.508)
			(layers "F.Cu" "F.Mask" "F.Paste")
			(net "GND")
		)
		(pad "260" smd rect
			(at 4.59994 102.849934 90)
			(size 1.8034 0.508)
			(layers "F.Cu" "F.Mask" "F.Paste")
			(net "M_J_DQ<42>")
		)
		(pad "261" smd rect
			(at 4.59994 103.700072 90)
			(size 1.8034 0.508)
			(layers "F.Cu" "F.Mask" "F.Paste")
			(net "GND")
		)
		(pad "262" smd rect
			(at 4.59994 104.549956 90)
			(size 1.8034 0.508)
			(layers "F.Cu" "F.Mask" "F.Paste")
			(net "M_J_DQ<52>")
		)
		(pad "263" smd rect
			(at 4.59994 105.400094 90)
			(size 1.8034 0.508)
			(layers "F.Cu" "F.Mask" "F.Paste")
			(net "GND")
		)
		(pad "264" smd rect
			(at 4.59994 106.249978 90)
			(size 1.8034 0.508)
			(layers "F.Cu" "F.Mask" "F.Paste")
			(net "M_J_DQ<48>")
		)
		(pad "265" smd rect
			(at 4.59994 107.100116 90)
			(size 1.8034 0.508)
			(layers "F.Cu" "F.Mask" "F.Paste")
			(net "GND")
		)
		(pad "266" smd rect
			(at 4.59994 107.95 90)
			(size 1.8034 0.508)
			(layers "F.Cu" "F.Mask" "F.Paste")
			(net "M_J_DQS_DN<6>")
		)
		(pad "267" smd rect
			(at 4.59994 108.799884 90)
			(size 1.8034 0.508)
			(layers "F.Cu" "F.Mask" "F.Paste")
			(net "M_J_DQS_DP<6>")
		)
		(pad "268" smd rect
			(at 4.59994 109.650022 90)
			(size 1.8034 0.508)
			(layers "F.Cu" "F.Mask" "F.Paste")
			(net "GND")
		)
		(pad "269" smd rect
			(at 4.59994 110.499906 90)
			(size 1.8034 0.508)
			(layers "F.Cu" "F.Mask" "F.Paste")
			(net "M_J_DQ<54>")
		)
		(pad "270" smd rect
			(at 4.59994 111.350044 90)
			(size 1.8034 0.508)
			(layers "F.Cu" "F.Mask" "F.Paste")
			(net "GND")
		)
		(pad "271" smd rect
			(at 4.59994 112.199928 90)
			(size 1.8034 0.508)
			(layers "F.Cu" "F.Mask" "F.Paste")
			(net "M_J_DQ<50>")
		)
		(pad "272" smd rect
			(at 4.59994 113.050066 90)
			(size 1.8034 0.508)
			(layers "F.Cu" "F.Mask" "F.Paste")
			(net "GND")
		)
		(pad "273" smd rect
			(at 4.59994 113.89995 90)
			(size 1.8034 0.508)
			(layers "F.Cu" "F.Mask" "F.Paste")
			(net "M_J_DQ<60>")
		)
		(pad "274" smd rect
			(at 4.59994 114.750088 90)
			(size 1.8034 0.508)
			(layers "F.Cu" "F.Mask" "F.Paste")
			(net "GND")
		)
		(pad "275" smd rect
			(at 4.59994 115.599972 90)
			(size 1.8034 0.508)
			(layers "F.Cu" "F.Mask" "F.Paste")
			(net "M_J_DQ<56>")
		)
		(pad "276" smd rect
			(at 4.59994 116.45011 90)
			(size 1.8034 0.508)
			(layers "F.Cu" "F.Mask" "F.Paste")
			(net "GND")
		)
		(pad "277" smd rect
			(at 4.59994 117.299994 90)
			(size 1.8034 0.508)
			(layers "F.Cu" "F.Mask" "F.Paste")
			(net "M_J_DQS_DN<7>")
		)
		(pad "278" smd rect
			(at 4.59994 118.149878 90)
			(size 1.8034 0.508)
			(layers "F.Cu" "F.Mask" "F.Paste")
			(net "M_J_DQS_DP<7>")
		)
		(pad "279" smd rect
			(at 4.59994 119.000016 90)
			(size 1.8034 0.508)
			(layers "F.Cu" "F.Mask" "F.Paste")
			(net "GND")
		)
		(pad "280" smd rect
			(at 4.59994 119.8499 90)
			(size 1.8034 0.508)
			(layers "F.Cu" "F.Mask" "F.Paste")
			(net "M_J_DQ<62>")
		)
		(pad "281" smd rect
			(at 4.59994 120.700038 90)
			(size 1.8034 0.508)
			(layers "F.Cu" "F.Mask" "F.Paste")
			(net "GND")
		)
		(pad "282" smd rect
			(at 4.59994 121.549922 90)
			(size 1.8034 0.508)
			(layers "F.Cu" "F.Mask" "F.Paste")
			(net "M_J_DQ<58>")
		)
		(pad "283" smd rect
			(at 4.59994 122.40006 90)
			(size 1.8034 0.508)
			(layers "F.Cu" "F.Mask" "F.Paste")
			(net "GND")
		)
		(pad "284" smd rect
			(at 4.59994 123.249944 90)
			(size 1.8034 0.508)
			(layers "F.Cu" "F.Mask" "F.Paste")
			(net "PVPP_GHJ")
		)
		(pad "285" smd rect
			(at 4.59994 124.100082 90)
			(size 1.8034 0.508)
			(layers "F.Cu" "F.Mask" "F.Paste")
			(net "SMB_DDR_GHJ_VPP_SDA")
		)
		(pad "286" smd rect
			(at 4.59994 124.949966 90)
			(size 1.8034 0.508)
			(layers "F.Cu" "F.Mask" "F.Paste")
			(net "PVPP_GHJ")
		)
		(pad "287" smd rect
			(at 4.59994 125.800104 90)
			(size 1.8034 0.508)
			(layers "F.Cu" "F.Mask" "F.Paste")
			(net "PVPP_GHJ")
		)
		(pad "288" smd rect
			(at 4.59994 126.649988 90)
			(size 1.8034 0.508)
			(layers "F.Cu" "F.Mask" "F.Paste")
			(net "PVPP_GHJ")
		)
	)
)
